(kicad_pcb
	(version 20260206)
	(generator "pcbnew")
	(generator_version "10.0")
	(general
		(thickness 1.6)
		(legacy_teardrops no)
	)
	(paper "A4")
	(title_block
		(title "03242023_DA0F0TMBIJ0_F0T_Motherboard_J_brd_V01_OCP.brd")
		(comment 1 "Grand Teton / footprints 779-784 of 6105")
	)
	(layers
		(0 "F.Cu" signal "TOP")
		(4 "In1.Cu" signal "GND")
		(6 "In2.Cu" signal "IN1")
		(8 "In3.Cu" signal "GND1")
		(10 "In4.Cu" signal "IN2")
		(12 "In5.Cu" signal "GND2")
		(14 "In6.Cu" signal "IN3")
		(16 "In7.Cu" signal "GND3")
		(18 "In8.Cu" signal "VCC")
		(20 "In9.Cu" signal "VCC1")
		(22 "In10.Cu" signal "GND4")
		(24 "In11.Cu" signal "IN4")
		(26 "In12.Cu" signal "GND5")
		(28 "In13.Cu" signal "IN5")
		(30 "In14.Cu" signal "GND6")
		(32 "In15.Cu" signal "IN6")
		(34 "In16.Cu" signal "GND7")
		(2 "B.Cu" signal "BOTTOM")
		(9 "F.Adhes" user "F.Adhesive")
		(11 "B.Adhes" user "B.Adhesive")
		(13 "F.Paste" user "Package Geometry/Pastemask Top")
		(15 "B.Paste" user "Package Geometry/Pastemask Bottom")
		(5 "F.SilkS" user "Ref Des/Silkscreen Top")
		(7 "B.SilkS" user "Ref Des/Silkscreen Bottom")
		(1 "F.Mask" user "Board Geometry/Soldermask Top")
		(3 "B.Mask" user "Board Geometry/Soldermask Bottom")
		(17 "Dwgs.User" user "User.Drawings")
		(19 "Cmts.User" user "User.Comments")
		(21 "Eco1.User" user "User.Eco1")
		(23 "Eco2.User" user "User.Eco2")
		(25 "Edge.Cuts" user "Board Geometry/Outline")
		(27 "Margin" user)
		(31 "F.CrtYd" user "Package Geometry/Place Bound Top")
		(29 "B.CrtYd" user "Package Geometry/Place Bound Bottom")
		(35 "F.Fab" user "Ref Des/Assembly Top")
		(33 "B.Fab" user "Ref Des/Assembly Bottom")
	)
	(footprint ""
		(layer "F.Cu")
		(at 152.96388 -129.758948 180)
		(property "Reference" "R3206"
			(at 0 0 180)
			(layer "F.SilkS")
			(hide yes)
			(effects
				(font
					(size 1.27 1.27)
				)
			)
		)
		(property "Value" ""
			(at 0 0 180)
			(layer "F.Fab")
			(effects
				(font
					(size 1.27 1.27)
				)
			)
		)
		(duplicate_pad_numbers_are_jumpers no)
		(fp_line
			(start 0.7874 0.4064)
			(end -0.7874 0.4064)
			(stroke
				(width 0.1524)
				(type default)
			)
			(layer "F.SilkS")
		)
		(fp_line
			(start 0.7874 -0.4064)
			(end 0.7874 0.4064)
			(stroke
				(width 0.1524)
				(type default)
			)
			(layer "F.SilkS")
		)
		(fp_line
			(start -0.7874 0.4064)
			(end -0.7874 -0.4064)
			(stroke
				(width 0.1524)
				(type default)
			)
			(layer "F.SilkS")
		)
		(fp_line
			(start -0.7874 -0.4064)
			(end 0.7874 -0.4064)
			(stroke
				(width 0.1524)
				(type default)
			)
			(layer "F.SilkS")
		)
		(fp_line
			(start 0.67945 0.3048)
			(end 0.120396 0.3048)
			(stroke
				(width 0.1)
				(type default)
			)
			(layer "F.Fab")
		)
		(fp_line
			(start 0.67945 -0.3048)
			(end 0.67945 0.3048)
			(stroke
				(width 0.1)
				(type default)
			)
			(layer "F.Fab")
		)
		(fp_line
			(start 0.12065 -0.2794)
			(end 0.12065 -0.3048)
			(stroke
				(width 0.1)
				(type default)
			)
			(layer "F.Fab")
		)
		(fp_line
			(start 0.12065 -0.3048)
			(end 0.67945 -0.3048)
			(stroke
				(width 0.1)
				(type default)
			)
			(layer "F.Fab")
		)
		(fp_line
			(start 0.120396 0.3048)
			(end 0.120396 0.2794)
			(stroke
				(width 0.1)
				(type default)
			)
			(layer "F.Fab")
		)
		(fp_line
			(start 0.120396 0.2794)
			(end -0.12065 0.2794)
			(stroke
				(width 0.1)
				(type default)
			)
			(layer "F.Fab")
		)
		(fp_line
			(start -0.12065 0.3048)
			(end -0.67945 0.3048)
			(stroke
				(width 0.1)
				(type default)
			)
			(layer "F.Fab")
		)
		(fp_line
			(start -0.12065 0.2794)
			(end -0.12065 0.3048)
			(stroke
				(width 0.1)
				(type default)
			)
			(layer "F.Fab")
		)
		(fp_line
			(start -0.12065 -0.2794)
			(end 0.12065 -0.2794)
			(stroke
				(width 0.1)
				(type default)
			)
			(layer "F.Fab")
		)
		(fp_line
			(start -0.12065 -0.305054)
			(end -0.12065 -0.2794)
			(stroke
				(width 0.1)
				(type default)
			)
			(layer "F.Fab")
		)
		(fp_line
			(start -0.67945 0.3048)
			(end -0.67945 -0.305054)
			(stroke
				(width 0.1)
				(type default)
			)
			(layer "F.Fab")
		)
		(fp_line
			(start -0.67945 -0.305054)
			(end -0.12065 -0.305054)
			(stroke
				(width 0.1)
				(type default)
			)
			(layer "F.Fab")
		)
		(pad "1" smd circle
			(at -0.40005 0 180)
			(size 0 0)
			(layers "F.Cu" "F.Mask" "F.Paste")
			(net "FM_NCSI_OCP_V3_2_R_OE")
		)
		(pad "2" smd circle
			(at 0.40005 0 180)
			(size 0 0)
			(layers "F.Cu" "F.Mask" "F.Paste")
			(net "FB_BMC_ISOLATE1")
		)
	)
	(footprint ""
		(layer "F.Cu")
		(at 187.28944 -355.90607)
		(property "Reference" "PC1681"
			(at 0 0 0)
			(layer "F.SilkS")
			(hide yes)
			(effects
				(font
					(size 1.27 1.27)
				)
			)
		)
		(property "Value" ""
			(at 0 0 0)
			(layer "F.Fab")
			(effects
				(font
					(size 1.27 1.27)
				)
			)
		)
		(duplicate_pad_numbers_are_jumpers no)
		(fp_line
			(start -1.524 -0.762)
			(end 1.524 -0.762)
			(stroke
				(width 0.1524)
				(type default)
			)
			(layer "F.SilkS")
		)
		(fp_line
			(start -1.524 0.762)
			(end -1.524 -0.762)
			(stroke
				(width 0.1524)
				(type default)
			)
			(layer "F.SilkS")
		)
		(fp_line
			(start 1.524 -0.762)
			(end 1.524 0.762)
			(stroke
				(width 0.1524)
				(type default)
			)
			(layer "F.SilkS")
		)
		(fp_line
			(start 1.524 0.762)
			(end -1.524 0.762)
			(stroke
				(width 0.1524)
				(type default)
			)
			(layer "F.SilkS")
		)
		(fp_line
			(start -1.1049 -0.724916)
			(end -1.1049 0.724916)
			(stroke
				(width 0.1)
				(type default)
			)
			(layer "F.Fab")
		)
		(fp_line
			(start -1.1049 0.724916)
			(end 1.1049 0.724916)
			(stroke
				(width 0.1)
				(type default)
			)
			(layer "F.Fab")
		)
		(fp_line
			(start 1.1049 -0.724916)
			(end -1.1049 -0.724916)
			(stroke
				(width 0.1)
				(type default)
			)
			(layer "F.Fab")
		)
		(fp_line
			(start 1.1049 0.724916)
			(end 1.1049 -0.724916)
			(stroke
				(width 0.1)
				(type default)
			)
			(layer "F.Fab")
		)
		(pad "1" smd rect
			(at -0.889 0 180)
			(size 1.016 1.27)
			(layers "F.Cu" "F.Mask" "F.Paste")
			(net "SW_P12V_PVCCFA_EHV_FIVRA_CPU1_R")
		)
		(pad "2" smd rect
			(at 0.889 0 180)
			(size 1.016 1.27)
			(layers "F.Cu" "F.Mask" "F.Paste")
			(net "GND")
		)
	)
	(footprint ""
		(layer "F.Cu")
		(at 221.67088 -44.922948 180)
		(property "Reference" "R3532"
			(at 0 0 180)
			(layer "F.SilkS")
			(hide yes)
			(effects
				(font
					(size 1.27 1.27)
				)
			)
		)
		(property "Value" ""
			(at 0 0 180)
			(layer "F.Fab")
			(effects
				(font
					(size 1.27 1.27)
				)
			)
		)
		(duplicate_pad_numbers_are_jumpers no)
		(fp_line
			(start 0.7874 0.4064)
			(end -0.7874 0.4064)
			(stroke
				(width 0.1524)
				(type default)
			)
			(layer "F.SilkS")
		)
		(fp_line
			(start 0.7874 -0.4064)
			(end 0.7874 0.4064)
			(stroke
				(width 0.1524)
				(type default)
			)
			(layer "F.SilkS")
		)
		(fp_line
			(start -0.7874 0.4064)
			(end -0.7874 -0.4064)
			(stroke
				(width 0.1524)
				(type default)
			)
			(layer "F.SilkS")
		)
		(fp_line
			(start -0.7874 -0.4064)
			(end 0.7874 -0.4064)
			(stroke
				(width 0.1524)
				(type default)
			)
			(layer "F.SilkS")
		)
		(fp_line
			(start 0.67945 0.3048)
			(end 0.120396 0.3048)
			(stroke
				(width 0.1)
				(type default)
			)
			(layer "F.Fab")
		)
		(fp_line
			(start 0.67945 -0.3048)
			(end 0.67945 0.3048)
			(stroke
				(width 0.1)
				(type default)
			)
			(layer "F.Fab")
		)
		(fp_line
			(start 0.12065 -0.2794)
			(end 0.12065 -0.3048)
			(stroke
				(width 0.1)
				(type default)
			)
			(layer "F.Fab")
		)
		(fp_line
			(start 0.12065 -0.3048)
			(end 0.67945 -0.3048)
			(stroke
				(width 0.1)
				(type default)
			)
			(layer "F.Fab")
		)
		(fp_line
			(start 0.120396 0.3048)
			(end 0.120396 0.2794)
			(stroke
				(width 0.1)
				(type default)
			)
			(layer "F.Fab")
		)
		(fp_line
			(start 0.120396 0.2794)
			(end -0.12065 0.2794)
			(stroke
				(width 0.1)
				(type default)
			)
			(layer "F.Fab")
		)
		(fp_line
			(start -0.12065 0.3048)
			(end -0.67945 0.3048)
			(stroke
				(width 0.1)
				(type default)
			)
			(layer "F.Fab")
		)
		(fp_line
			(start -0.12065 0.2794)
			(end -0.12065 0.3048)
			(stroke
				(width 0.1)
				(type default)
			)
			(layer "F.Fab")
		)
		(fp_line
			(start -0.12065 -0.2794)
			(end 0.12065 -0.2794)
			(stroke
				(width 0.1)
				(type default)
			)
			(layer "F.Fab")
		)
		(fp_line
			(start -0.12065 -0.305054)
			(end -0.12065 -0.2794)
			(stroke
				(width 0.1)
				(type default)
			)
			(layer "F.Fab")
		)
		(fp_line
			(start -0.67945 0.3048)
			(end -0.67945 -0.305054)
			(stroke
				(width 0.1)
				(type default)
			)
			(layer "F.Fab")
		)
		(fp_line
			(start -0.67945 -0.305054)
			(end -0.12065 -0.305054)
			(stroke
				(width 0.1)
				(type default)
			)
			(layer "F.Fab")
		)
		(pad "1" smd circle
			(at -0.40005 0 180)
			(size 0 0)
			(layers "F.Cu" "F.Mask" "F.Paste")
			(net "P3V3_E1S_0")
		)
		(pad "2" smd circle
			(at 0.40005 0 180)
			(size 0 0)
			(layers "F.Cu" "F.Mask" "F.Paste")
			(net "SMB_E1S_3V3AUX_ISO_SDA_R")
		)
	)
	(footprint ""
		(layer "F.Cu")
		(at 118.542816 -238.162592 90)
		(property "Reference" "C438"
			(at 0 0 90)
			(layer "F.SilkS")
			(hide yes)
			(effects
				(font
					(size 1.27 1.27)
				)
			)
		)
		(property "Value" ""
			(at 0 0 90)
			(layer "F.Fab")
			(effects
				(font
					(size 1.27 1.27)
				)
			)
		)
		(duplicate_pad_numbers_are_jumpers no)
		(fp_line
			(start 0.7874 -0.4064)
			(end 0.7874 0.4064)
			(stroke
				(width 0.1524)
				(type default)
			)
			(layer "F.SilkS")
		)
		(fp_line
			(start -0.7874 -0.4064)
			(end 0.7874 -0.4064)
			(stroke
				(width 0.1524)
				(type default)
			)
			(layer "F.SilkS")
		)
		(fp_line
			(start 0.7874 0.4064)
			(end -0.7874 0.4064)
			(stroke
				(width 0.1524)
				(type default)
			)
			(layer "F.SilkS")
		)
		(fp_line
			(start -0.7874 0.4064)
			(end -0.7874 -0.4064)
			(stroke
				(width 0.1524)
				(type default)
			)
			(layer "F.SilkS")
		)
		(fp_line
			(start -0.12065 -0.305054)
			(end -0.12065 -0.2794)
			(stroke
				(width 0.1)
				(type default)
			)
			(layer "F.Fab")
		)
		(fp_line
			(start -0.67945 -0.305054)
			(end -0.12065 -0.305054)
			(stroke
				(width 0.1)
				(type default)
			)
			(layer "F.Fab")
		)
		(fp_line
			(start 0.67945 -0.3048)
			(end 0.67945 0.3048)
			(stroke
				(width 0.1)
				(type default)
			)
			(layer "F.Fab")
		)
		(fp_line
			(start 0.12065 -0.3048)
			(end 0.67945 -0.3048)
			(stroke
				(width 0.1)
				(type default)
			)
			(layer "F.Fab")
		)
		(fp_line
			(start 0.12065 -0.2794)
			(end 0.12065 -0.3048)
			(stroke
				(width 0.1)
				(type default)
			)
			(layer "F.Fab")
		)
		(fp_line
			(start -0.12065 -0.2794)
			(end 0.12065 -0.2794)
			(stroke
				(width 0.1)
				(type default)
			)
			(layer "F.Fab")
		)
		(fp_line
			(start 0.120396 0.2794)
			(end -0.12065 0.2794)
			(stroke
				(width 0.1)
				(type default)
			)
			(layer "F.Fab")
		)
		(fp_line
			(start -0.12065 0.2794)
			(end -0.12065 0.3048)
			(stroke
				(width 0.1)
				(type default)
			)
			(layer "F.Fab")
		)
		(fp_line
			(start 0.67945 0.3048)
			(end 0.120396 0.3048)
			(stroke
				(width 0.1)
				(type default)
			)
			(layer "F.Fab")
		)
		(fp_line
			(start 0.120396 0.3048)
			(end 0.120396 0.2794)
			(stroke
				(width 0.1)
				(type default)
			)
			(layer "F.Fab")
		)
		(fp_line
			(start -0.12065 0.3048)
			(end -0.67945 0.3048)
			(stroke
				(width 0.1)
				(type default)
			)
			(layer "F.Fab")
		)
		(fp_line
			(start -0.67945 0.3048)
			(end -0.67945 -0.305054)
			(stroke
				(width 0.1)
				(type default)
			)
			(layer "F.Fab")
		)
		(pad "1" smd circle
			(at -0.40005 0 90)
			(size 0 0)
			(layers "F.Cu" "F.Mask" "F.Paste")
			(net "PVCCINFAON_CPU1")
		)
		(pad "2" smd circle
			(at 0.40005 0 90)
			(size 0 0)
			(layers "F.Cu" "F.Mask" "F.Paste")
			(net "GND")
		)
	)
	(footprint ""
		(layer "F.Cu")
		(at 101.071172 -362.602526)
		(property "Reference" "R2455"
			(at 0 0 0)
			(layer "F.SilkS")
			(hide yes)
			(effects
				(font
					(size 1.27 1.27)
				)
			)
		)
		(property "Value" ""
			(at 0 0 0)
			(layer "F.Fab")
			(effects
				(font
					(size 1.27 1.27)
				)
			)
		)
		(duplicate_pad_numbers_are_jumpers no)
		(fp_line
			(start -0.7874 -0.4064)
			(end 0.7874 -0.4064)
			(stroke
				(width 0.1524)
				(type default)
			)
			(layer "F.SilkS")
		)
		(fp_line
			(start -0.7874 0.4064)
			(end -0.7874 -0.4064)
			(stroke
				(width 0.1524)
				(type default)
			)
			(layer "F.SilkS")
		)
		(fp_line
			(start 0.7874 -0.4064)
			(end 0.7874 0.4064)
			(stroke
				(width 0.1524)
				(type default)
			)
			(layer "F.SilkS")
		)
		(fp_line
			(start 0.7874 0.4064)
			(end -0.7874 0.4064)
			(stroke
				(width 0.1524)
				(type default)
			)
			(layer "F.SilkS")
		)
		(fp_line
			(start -0.67945 -0.305054)
			(end -0.12065 -0.305054)
			(stroke
				(width 0.1)
				(type default)
			)
			(layer "F.Fab")
		)
		(fp_line
			(start -0.67945 0.3048)
			(end -0.67945 -0.305054)
			(stroke
				(width 0.1)
				(type default)
			)
			(layer "F.Fab")
		)
		(fp_line
			(start -0.12065 -0.305054)
			(end -0.12065 -0.2794)
			(stroke
				(width 0.1)
				(type default)
			)
			(layer "F.Fab")
		)
		(fp_line
			(start -0.12065 -0.2794)
			(end 0.12065 -0.2794)
			(stroke
				(width 0.1)
				(type default)
			)
			(layer "F.Fab")
		)
		(fp_line
			(start -0.12065 0.2794)
			(end -0.12065 0.3048)
			(stroke
				(width 0.1)
				(type default)
			)
			(layer "F.Fab")
		)
		(fp_line
			(start -0.12065 0.3048)
			(end -0.67945 0.3048)
			(stroke
				(width 0.1)
				(type default)
			)
			(layer "F.Fab")
		)
		(fp_line
			(start 0.120396 0.2794)
			(end -0.12065 0.2794)
			(stroke
				(width 0.1)
				(type default)
			)
			(layer "F.Fab")
		)
		(fp_line
			(start 0.120396 0.3048)
			(end 0.120396 0.2794)
			(stroke
				(width 0.1)
				(type default)
			)
			(layer "F.Fab")
		)
		(fp_line
			(start 0.12065 -0.3048)
			(end 0.67945 -0.3048)
			(stroke
				(width 0.1)
				(type default)
			)
			(layer "F.Fab")
		)
		(fp_line
			(start 0.12065 -0.2794)
			(end 0.12065 -0.3048)
			(stroke
				(width 0.1)
				(type default)
			)
			(layer "F.Fab")
		)
		(fp_line
			(start 0.67945 -0.3048)
			(end 0.67945 0.3048)
			(stroke
				(width 0.1)
				(type default)
			)
			(layer "F.Fab")
		)
		(fp_line
			(start 0.67945 0.3048)
			(end 0.120396 0.3048)
			(stroke
				(width 0.1)
				(type default)
			)
			(layer "F.Fab")
		)
		(pad "1" smd circle
			(at -0.40005 0)
			(size 0 0)
			(layers "F.Cu" "F.Mask" "F.Paste")
			(net "SMB_VR_3V3AUX_SCL_R")
		)
		(pad "2" smd circle
			(at 0.40005 0)
			(size 0 0)
			(layers "F.Cu" "F.Mask" "F.Paste")
			(net "SMB_VR_3V3AUX_SCL_R3")
		)
	)
	(footprint ""
		(layer "F.Cu")
		(at 336.018124 -25.070562 -90)
		(property "Reference" "R1479"
			(at 0 0 270)
			(layer "F.SilkS")
			(hide yes)
			(effects
				(font
					(size 1.27 1.27)
				)
			)
		)
		(property "Value" ""
			(at 0 0 270)
			(layer "F.Fab")
			(effects
				(font
					(size 1.27 1.27)
				)
			)
		)
		(duplicate_pad_numbers_are_jumpers no)
		(fp_line
			(start -0.7874 0.4064)
			(end -0.7874 -0.4064)
			(stroke
				(width 0.1524)
				(type default)
			)
			(layer "F.SilkS")
		)
		(fp_line
			(start 0.7874 0.4064)
			(end -0.7874 0.4064)
			(stroke
				(width 0.1524)
				(type default)
			)
			(layer "F.SilkS")
		)
		(fp_line
			(start -0.7874 -0.4064)
			(end 0.7874 -0.4064)
			(stroke
				(width 0.1524)
				(type default)
			)
			(layer "F.SilkS")
		)
		(fp_line
			(start 0.7874 -0.4064)
			(end 0.7874 0.4064)
			(stroke
				(width 0.1524)
				(type default)
			)
			(layer "F.SilkS")
		)
		(fp_line
			(start -0.67945 0.3048)
			(end -0.67945 -0.305054)
			(stroke
				(width 0.1)
				(type default)
			)
			(layer "F.Fab")
		)
		(fp_line
			(start -0.12065 0.3048)
			(end -0.67945 0.3048)
			(stroke
				(width 0.1)
				(type default)
			)
			(layer "F.Fab")
		)
		(fp_line
			(start 0.120396 0.3048)
			(end 0.120396 0.2794)
			(stroke
				(width 0.1)
				(type default)
			)
			(layer "F.Fab")
		)
		(fp_line
			(start 0.67945 0.3048)
			(end 0.120396 0.3048)
			(stroke
				(width 0.1)
				(type default)
			)
			(layer "F.Fab")
		)
		(fp_line
			(start -0.12065 0.2794)
			(end -0.12065 0.3048)
			(stroke
				(width 0.1)
				(type default)
			)
			(layer "F.Fab")
		)
		(fp_line
			(start 0.120396 0.2794)
			(end -0.12065 0.2794)
			(stroke
				(width 0.1)
				(type default)
			)
			(layer "F.Fab")
		)
		(fp_line
			(start -0.12065 -0.2794)
			(end 0.12065 -0.2794)
			(stroke
				(width 0.1)
				(type default)
			)
			(layer "F.Fab")
		)
		(fp_line
			(start 0.12065 -0.2794)
			(end 0.12065 -0.3048)
			(stroke
				(width 0.1)
				(type default)
			)
			(layer "F.Fab")
		)
		(fp_line
			(start 0.12065 -0.3048)
			(end 0.67945 -0.3048)
			(stroke
				(width 0.1)
				(type default)
			)
			(layer "F.Fab")
		)
		(fp_line
			(start 0.67945 -0.3048)
			(end 0.67945 0.3048)
			(stroke
				(width 0.1)
				(type default)
			)
			(layer "F.Fab")
		)
		(fp_line
			(start -0.67945 -0.305054)
			(end -0.12065 -0.305054)
			(stroke
				(width 0.1)
				(type default)
			)
			(layer "F.Fab")
		)
		(fp_line
			(start -0.12065 -0.305054)
			(end -0.12065 -0.2794)
			(stroke
				(width 0.1)
				(type default)
			)
			(layer "F.Fab")
		)
		(pad "1" smd circle
			(at -0.40005 0 270)
			(size 0 0)
			(layers "F.Cu" "F.Mask" "F.Paste")
			(net "ESPI_LFRAME_N_BMC_CS0_N")
		)
		(pad "2" smd circle
			(at 0.40005 0 270)
			(size 0 0)
			(layers "F.Cu" "F.Mask" "F.Paste")
			(net "ESPI_HOST_LPC_BMC_LFRAME_N")
		)
	)
)
